FILE_TYPE = CONNECTIVITY;
{Allegro Design Entry HDL 16.6-p007 (v16-6-112F) 10/10/2012}
"PAGE_NUMBER" = 234;
0"NC";
1"GND\g";
2"P3V3_STBY\g";
3"GND\g";
4"P12V_STBY\g";
5"GND\g";
6"GND\g";
7"GND\g";
8"GND\g";
9"GND\g";
10"GND\g";
11"GND\g";
12"PVPP_KLM\g";
13"AGND_PVPP_KLM\g";
14"AGND_PVPP_KLM\g";
15"AGND_PVPP_KLM\g";
16"AGND_PVPP_KLM\g";
17"AGND_PVPP_KLM\g";
18"GND\g";
19"AGND_PVPP_KLM\g";
20"GND\g";
21"GND\g";
22"GND\g";
23"GND\g";
24"AGND_PVPP_KLM\g";
25"GND\g";
26"GND\g";
27"GND\g";
28"AGND_PVPP_KLM\g";
29"GND\g";
30"PVPP_KLM\g";
31"VR_FET_SW_P12V_STBY_PVPP_KLM";
32"FM_PVPP_PVDDQ_CPU1_EN_KLM";
33"VR_PVPP_KLM_SS";
34"VR_PVPP_KLM_SNUB";
35"PWRGD_PVPP_KLM";
36"FM_PVPP_CPU1_EN";
37"VR_PVPP_KLM_PHASE";
38"VR_PVPP_KLM_BOOT_R";
39"VR_COMP_PVPP_KLM_3";
40"VSENSE_PVPP_KLM";
41"VR_COMP_PVPP_KLM";
42"VR_COMP_RC_PVPP_KLM";
43"VR_PVPP_KLM_BOOT";
44"VR_VB_PVPP_KLM";
45"VR_FB_PVPP_KLM";
46"VR_PVPP_KLM_ISET";
47"PWRGD_PVPP_KLM_R";
%"CAP"
"1","(-6300,2400)","2","mstr_discrete","I129";
;
PACK_TYPE"0402LF"
PART_NUMBER"A36096-046"
MATERIAL"EMPTY"
TOLERANCE"10%"
VOLTAGE"50V"
VALUE"1000PF"
LOCATION"C4B5"
FIN"VR_1P2"
REUSE_ID"1"
CDS_SEC"1"
$SEC"1"
CDS_LOCATION"C4B5"
CDS_LIB"mstr_discrete"
BOM_COST"PVPP_KLM_VR"
ROOM"PVPP_KLM_VR";
"A"
$PN"1"36;
"B"
$PN"2"13;
%"GND"
"1","(-3875,475)","0","mstr_symbols","I138";
;
HDL_POWER"GND"
CDS_LIB"mstr_symbols"
VOLTAGE"0"
SIZE"1B"
BODY_TYPE"PLUMBING"
ROOM"PVPP_KLM_VR"
BOM_COST"PVPP_KLM_VR";
"A\NAC"1;
%"CAP"
"1","(-3875,725)","0","mstr_discrete","I139";
;
VALUE"1000PF"
PACK_TYPE"0402LF"
PART_NUMBER"A36096-046"
VOLTAGE"50V"
MATERIAL"X7R"
LOCATION"C4B8"
TOLERANCE"10%"
CDS_LOCATION"C4B8"
$SEC"1"
CDS_SEC"1"
REUSE_ID"17"
BOM_COST"PVPP_KLM_VR"
CDS_LIB"mstr_discrete"
ROOM"PVPP_KLM_VR";
"A"
$PN"1"47;
"B"
$PN"2"1;
%"P3V3_STBY"
"1","(-4225,1525)","0","mstr_symbols","I142";
;
VOLTAGE"+3.3V"
SIZE"1B"
CDS_LIB"mstr_symbols"
BODY_TYPE"PLUMBING"
HDL_POWER"P3V3_STBY";
"G\NAC"2;
%"RES"
"2","(-4225,1250)","0","mstr_discrete","I143";
;
CDS_SEC"1"
LOCATION"R4B10"
PART_NUMBER"G21796-026"
VALUE"1.00K"
PACK_TYPE"0402"
MATERIAL"CHIP"
WATTAGE"1/16W"
TOLERANCE"1%"
ROOM"PVPP_KLM_VR"
CDS_LOCATION"R4B10"
SEC"1"
SEC_TYPE"0402"
BOM_COST"PVPP_KLM_VR"
REUSE_ID"21"
CDS_LIB"mstr_discrete";
"A"
$PN"1"2;
"B"
$PN"2"47;
%"CAP"
"1","(-5650,2400)","0","mstr_discrete","I144";
;
CDS_SEC"1"
CDS_LOCATION"C6L12"
TOLERANCE"10%"
PART_NUMBER"E15431-003"
PACK_TYPE"0603"
VOLTAGE"6.3V"
VALUE"4.7UF"
LOCATION"C6L12"
MATERIAL"X6S"
CONFIG"078.47521.08BD"
CDS_LIB"mstr_discrete"
ROOM"PVPP_KLM_VR"
BOM_COST"PVPP_KLM_VR"
SEC_TYPE"0603"
REUSE_ID"26"
SEC"1";
"A"
$PN"1"44;
"B"
$PN"2"14;
%"CAP"
"1","(-5075,2175)","0","mstr_discrete","I146";
;
CDS_SEC"1"
LOCATION"C4B6"
TOLERANCE"10%"
VOLTAGE"16V"
VALUE"0.027UF"
PACK_TYPE"0402"
MATERIAL"X7R"
PART_NUMBER"A36096-129"
SEC"1"
REUSE_ID"26"
BOM_COST"PVPP_KLM_VR"
SEC_TYPE"0402"
ROOM"PVPP_KLM_VR"
CDS_LOCATION"C4B6"
CDS_LIB"mstr_discrete";
"A"
$PN"1"33;
"B"
$PN"2"15;
%"GND"
"1","(-5100,3900)","0","mstr_symbols","I151";
;
HDL_POWER"GND"
VOLTAGE"0"
CDS_LIB"mstr_symbols"
BODY_TYPE"PLUMBING"
SIZE"1B"
ROOM"PVPP_KLM_VR"
BOM_COST"PVPP_KLM_VR";
"A\NAC"3;
%"CAP"
"1","(-5100,4150)","0","mstr_discrete","I152";
;
TOLERANCE"10%"
MATERIAL"X6S"
PART_NUMBER"D97712-011"
PACK_TYPE"0402"
LOCATION"C6L11"
VALUE"1.0UF"
VOLTAGE"16V"
FIN"VR_1P2"
$SEC"1"
CDS_SEC"1"
REUSE_ID"1"
CDS_LOCATION"C6L11"
ROOM"PVPP_KLM_VR"
BOM_COST"PVPP_KLM_VR"
CDS_LIB"mstr_discrete";
"A"
$PN"1"31;
"B"
$PN"2"3;
%"P12V_STBY"
"1","(-7850,4500)","0","mstr_symbols","I153";
;
VOLTAGE"12.0V"
CDS_LIB"mstr_symbols"
SIZE"1B"
BODY_TYPE"PLUMBING"
HDL_POWER"P12V_STBY";
"G\NAC"4;
%"FERRITE"
"1","(-7650,4300)","0","mstr_discrete","I154";
;
CDS_SEC"1"
VALUE"22"
MATERIAL"FB"
LOCATION"FB4A1"
PACK_TYPE"SM"
PART_NUMBER"656554-051"
CDS_LIB"mstr_discrete"
TOLERANCE"1%"
SEC_TYPE"SM"
SEC"1"
CDS_LOCATION"FB4A1"
ROOM"PVPP_KLM_VR";
"A"
$PN"1"4;
"B"
$PN"2"31;
%"GND"
"1","(-3075,1925)","0","mstr_symbols","I157";
;
HDL_POWER"GND"
BOM_COST"PVPP_KLM_VR"
ROOM"PVPP_KLM_VR"
SIZE"1B"
BODY_TYPE"PLUMBING"
CDS_LIB"mstr_symbols"
VOLTAGE"0";
"A\NAC"5;
%"GND"
"1","(-2575,3100)","0","mstr_symbols","I161";
;
BOM_COST"PVPP_KLM_VR"
ROOM"PVPP_KLM_VR"
BODY_TYPE"PLUMBING"
SIZE"1B"
CDS_LIB"mstr_symbols"
VOLTAGE"0"
HDL_POWER"GND";
"A\NAC"6;
%"RES"
"2","(-2575,3275)","0","mstr_discrete","I162";
;
TOLERANCE"5%"
LOCATION"R4A7"
VALUE"2.2"
WATTAGE"1/16W"
PACK_TYPE"0402"
MATERIAL"EMPTY"
PART_NUMBER"G21497-016"
REUSE_ID"29"
CDS_SEC"1"
$SEC"1"
BOM_COST"PVPP_KLM_VR"
ROOM"PVPP_KLM_VR"
CDS_LOCATION"R4A7"
CDS_LIB"mstr_discrete";
"A"
$PN"1"34;
"B"
$PN"2"6;
%"CAP"
"1","(-2575,3600)","0","mstr_discrete","I163";
;
PART_NUMBER"A36096-091"
MATERIAL"EMPTY"
TOLERANCE"10%"
VALUE"3300PF"
PACK_TYPE"0402LF"
VOLTAGE"50V"
LOCATION"C4A16"
CDS_LOCATION"C4A16"
REUSE_ID"26"
BOM_COST"PVPP_KLM_VR"
CDS_SEC"1"
$SEC"1"
ROOM"PVPP_KLM_VR"
CDS_LIB"mstr_discrete";
"A"
$PN"1"37;
"B"
$PN"2"34;
%"INDUCTOR"
"1","(-2300,3850)","0","mstr_discrete","I164";
;
PACK_TYPE"SM"
PART_NUMBER"E13358-018"
LOCATION"L4A1"
VALUE"0.47UH"
MATERIAL"IND"
ROOM"PVPP_KLM_VR"
CDS_LIB"mstr_discrete"
BOM_COST"PVPP_KLM_VR"
REUSE_ID"30"
TOLERANCE"1%"
CDS_SEC"1"
$SEC"1"
CDS_LOCATION"L4A1";
"INA\NAC"
$PN"1"37;
"INB\NAC"
$PN"2"12;
%"GND"
"1","(-2050,3400)","0","mstr_symbols","I165";
;
BOM_COST"PVPP_KLM_VR"
ROOM"PVPP_KLM_VR"
BODY_TYPE"PLUMBING"
CDS_LIB"mstr_symbols"
VOLTAGE"0"
HDL_POWER"GND"
SIZE"1B";
"A\NAC"7;
%"GND"
"1","(-1750,3350)","0","mstr_symbols","I166";
;
HDL_POWER"GND"
SIZE"1B"
CDS_LIB"mstr_symbols"
VOLTAGE"0"
BODY_TYPE"PLUMBING"
ROOM"PVPP_KLM_VR"
BOM_COST"PVPP_KLM_VR";
"A\NAC"8;
%"CAPP"
"1","(-1750,3650)","0","mstr_discrete","I167";
;
PACK_TYPE"7343LF"
MATERIAL"POSCAP"
VOLTAGE"6.3V"
TOLERANCE"20%"
VALUE"330UF"
LOCATION"C3B3"
PART_NUMBER"724613-042"
GROUP"PWR_BULK_CAP"
REUSE_ID"28"
CDS_SEC"1"
$SEC"1"
CDS_LOCATION"C3B3"
CDS_LIB"mstr_discrete"
ROOM"PVPP_KLM_VR"
BOM_COST"PVPP_KLM_VR";
"B"
$PN"2"8;
"A"
$PN"1"12;
%"GND"
"1","(-1450,3350)","0","mstr_symbols","I175";
;
HDL_POWER"GND"
SIZE"1B"
VOLTAGE"0"
CDS_LIB"mstr_symbols"
BODY_TYPE"PLUMBING"
ROOM"PVPP_KLM_VR"
BOM_COST"PVPP_KLM_VR";
"A\NAC"9;
%"CAP"
"1","(-1150,3700)","0","mstr_discrete","I177";
;
PACK_TYPE"0805"
MATERIAL"X6S"
PART_NUMBER"C95333-006"
LOCATION"C4B3"
VALUE"47UF"
VOLTAGE"4V"
TOLERANCE"20%"
GROUP"PWR_MLCC_CAP"
CDS_LIB"mstr_discrete"
BOM_COST"PVPP_KLM_VR"
CDS_LOCATION"C4B3"
ROOM"PVPP_KLM_VR"
REUSE_ID"33"
CDS_SEC"1"
$SEC"1";
"A"
$PN"1"12;
"B"
$PN"2"10;
%"GND"
"1","(-1150,3350)","0","mstr_symbols","I178";
;
ROOM"PVPP_KLM_VR"
BOM_COST"PVPP_KLM_VR"
BODY_TYPE"PLUMBING"
SIZE"1B"
CDS_LIB"mstr_symbols"
VOLTAGE"0"
HDL_POWER"GND";
"A\NAC"10;
%"GND"
"1","(-850,3350)","0","mstr_symbols","I179";
;
HDL_POWER"GND"
VOLTAGE"0"
CDS_LIB"mstr_symbols"
BODY_TYPE"PLUMBING"
SIZE"1B"
ROOM"PVPP_KLM_VR"
BOM_COST"PVPP_KLM_VR";
"A\NAC"11;
%"CAP"
"1","(-850,3700)","0","mstr_discrete","I180";
;
MATERIAL"X6S"
PACK_TYPE"0805"
TOLERANCE"20%"
VALUE"47UF"
LOCATION"C4B2"
PART_NUMBER"C95333-006"
VOLTAGE"4V"
GROUP"PWR_MLCC_CAP"
ROOM"PVPP_KLM_VR"
CDS_LOCATION"C4B2"
BOM_COST"PVPP_KLM_VR"
CDS_LIB"mstr_discrete"
REUSE_ID"33"
CDS_SEC"1"
$SEC"1";
"A"
$PN"1"12;
"B"
$PN"2"11;
%"CAP"
"2","(-3375,4200)","2","mstr_discrete","I182";
;
CDS_LOCATION"C4B15"
TOLERANCE"10%"
PACK_TYPE"0603LF"
PART_NUMBER"602433-020"
VOLTAGE"25V"
MATERIAL"X7R"
VALUE"0.1UF"
LOCATION"C4B15"
$SEC"1"
CDS_SEC"1"
CDS_LIB"mstr_discrete"
ROOM"PVPP_KLM_VR"
REUSE_ID"27"
BOM_COST"PVPP_KLM_VR";
"A"
$PN"1"37;
"B"
$PN"2"38;
%"RES"
"2","(-2050,3650)","0","mstr_discrete","I183";
;
PART_NUMBER"G22026-003"
PACK_TYPE"0603"
LOCATION"R4B2"
VALUE"120.0"
TOLERANCE"1%"
WATTAGE"1/10W"
MATERIAL"CHIP"
CDS_LIB"mstr_discrete"
ROOM"PVPP_KLM_VR"
CDS_LOCATION"R4B2"
$SEC"1"
CDS_SEC"1"
BOM_COST"PVPP_KLM_VR"
REUSE_ID"34";
"A"
$PN"1"12;
"B"
$PN"2"7;
%"NCP3232L"
"1","(-3800,2875)","0","mstr_vreg","I184";
;
CDS_SEC"1"
PART_NUMBER"H86355-001"
MATERIAL"IC"
LOCATION"EU4A3"
CDS_LMAN_SYM_OUTLINE"-450,850,450,-900"
CDS_LIB"mstr_vreg"
PACK_TYPE"SM"
SEC_TYPE"SM"
SEC"1"
CDS_LOCATION"EU4A3";
"PG"
$PN"7"47;
"PGND<0>"
$PN"16"5;
"PGND<1>"
$PN"17"5;
"PGND<2>"
$PN"18"5;
"PGND<3>"
$PN"19"5;
"PGND<4>"
$PN"20"5;
"PGND<5>"
$PN"21"5;
"PGND<6>"
$PN"22"5;
"PGND<8>"
$PN"24"5;
"PGND<7>"
$PN"23"5;
"PGND<9>"
$PN"25"5;
"PGND<10>"
$PN"26"5;
"PGND<11>"
$PN"27"5;
"PGND<12>"
$PN"28"5;
"PGND<13>"
$PN"37"5;
"GND"
$PN"41"5;
"AGND"
$PN"5"17;
"EN"
$PN"40"32;
"SS"
$PN"1"33;
"ISET"
$PN"4"46;
"OTS"
$PN"6"19;
"VIN<6>"
$PN"14"31;
"VIN<7>"
$PN"42"31;
"VCC"
$PN"39"31;
"VIN<1>"
$PN"9"31;
"VIN<5>"
$PN"13"31;
"VIN<4>"
$PN"12"31;
"VIN<3>"
$PN"11"31;
"VIN<2>"
$PN"10"31;
"VIN<0>"
$PN"8"31;
"VB"
$PN"38"44;
"COMP"
$PN"3"39;
"FB"
$PN"2"45;
"VSWH<1>"
$PN"29"37;
"VSWH<0>"
$PN"15"37;
"VSW"
$PN"35"37;
"VSWH<2>"
$PN"30"37;
"VSWH<3>"
$PN"31"37;
"VSWH<4>"
$PN"32"37;
"VSWH<5>"
$PN"33"37;
"VSWH<6>"
$PN"34"37;
"BST"
$PN"36"43;
"VSWH<7>"
$PN"43"37;
%"PVPP_KLM"
"1","(-800,3975)","0","mstr_symbols","I185";
;
BOM_COST"PVPP_KLM_VR"
ROOM"PVPP_KLM_VR"
HDL_POWER"PVPP_KLM"
CDS_LIB"mstr_symbols"
BODY_TYPE"PLUMBING"
VOLTAGE"2.5V";
"G\NAC"12;
%"AGND_SCSI"
"1","(-6300,2075)","0","mstr_symbols","I187";
;
HDL_POWER"AGND_PVPP_KLM"
CDS_LIB"mstr_symbols"
BOM_COST"PVPP_KLM_VR"
ROOM"PVPP_KLM_VR"
VOLTAGE"0.0V"
BODY_TYPE"PLUMBING";
"A"13;
%"AGND_SCSI"
"1","(-5650,2150)","0","mstr_symbols","I188";
;
HDL_POWER"AGND_PVPP_KLM"
ROOM"PVPP_KLM_VR"
BODY_TYPE"PLUMBING"
BOM_COST"PVPP_KLM_VR"
VOLTAGE"0.0V"
CDS_LIB"mstr_symbols";
"A"14;
%"AGND_SCSI"
"1","(-5075,1950)","0","mstr_symbols","I189";
;
HDL_POWER"AGND_PVPP_KLM"
CDS_LIB"mstr_symbols"
VOLTAGE"0.0V"
BODY_TYPE"PLUMBING"
BOM_COST"PVPP_KLM_VR"
ROOM"PVPP_KLM_VR";
"A"15;
%"AGND_SCSI"
"1","(-4750,1350)","0","mstr_symbols","I190";
;
HDL_POWER"AGND_PVPP_KLM"
VOLTAGE"0"
CDS_LIB"mstr_symbols"
BODY_TYPE"PLUMBING";
"A"16;
%"AGND_SCSI"
"1","(-4375,1850)","0","mstr_symbols","I191";
;
HDL_POWER"AGND_PVPP_KLM"
BODY_TYPE"PLUMBING"
BOM_COST"PVPP_KLM_VR"
CDS_LIB"mstr_symbols"
VOLTAGE"0.0V"
ROOM"PVPP_KLM_VR";
"A"17;
%"GND"
"1","(-5175,3300)","0","mstr_symbols","I198";
;
SIZE"1B"
HDL_POWER"GND"
VOLTAGE"0"
CDS_LIB"mstr_symbols"
BODY_TYPE"PLUMBING"
BOM_COST"PVPP_KLM_VR"
ROOM"PVPP_KLM_VR";
"A\NAC"18;
%"CAP_A"
"1","(-5175,3525)","0","dev_discrete","I199";
;
PACK_TYPE"0402V"
PART_NUMBER"A36096-030"
VALUE"0.1UF"
LOCATION"C4A20"
TOLERANCE"10%"
VOLTAGE"16V"
MATERIAL"X7R"
CDS_LOCATION"C4A20"
CDS_SEC"1"
SEC_TYPE"0402V"
SEC"1"
CDS_LIB"dev_discrete";
"B"
$PN"2"18;
"A"
$PN"1"31;
%"AGND_SCSI"
"1","(-5400,2700)","0","mstr_symbols","I200";
;
HDL_POWER"AGND_PVPP_KLM"
VOLTAGE"0.0V"
BOM_COST"PVPP_KLM_VR"
CDS_LIB"mstr_symbols"
BODY_TYPE"PLUMBING"
ROOM"PVPP_KLM_VR";
"A"19;
%"RES"
"1","(-3350,975)","0","mstr_discrete","I201";
;
CDS_SEC"1"
PART_NUMBER"G21796-250"
VALUE"22.1"
TOLERANCE"1.0%"
WATTAGE"1/16W"
PACK_TYPE"0402"
LOCATION"R4B7"
MATERIAL"CHIP"
SEC_TYPE"0402"
SEC"1"
CDS_LOCATION"R4B7"
ROOM"PVPP_KLM_VR"
CDS_LIB"mstr_discrete";
"B"
$PN"2"35;
"A"
$PN"1"47;
%"CAP"
"1","(-6750,4150)","0","mstr_discrete","I202";
;
CDS_SEC"1"
VOLTAGE"16V"
PACK_TYPE"0805"
TOLERANCE"10%"
VALUE"10UF"
LOCATION"C6L10"
PART_NUMBER"C95333-007"
MATERIAL"X6S"
SEC"1"
SEC_TYPE"0805"
CDS_LOCATION"C6L10"
CDS_LIB"mstr_discrete";
"A"
$PN"1"31;
"B"
$PN"2"20;
%"CAP"
"1","(-6375,4150)","0","mstr_discrete","I203";
;
CDS_SEC"1"
TOLERANCE"10%"
MATERIAL"X6S"
VOLTAGE"16V"
PACK_TYPE"0805"
PART_NUMBER"C95333-007"
LOCATION"C6M3"
VALUE"10UF"
CDS_LIB"mstr_discrete"
CDS_LOCATION"C6M3"
SEC_TYPE"0805"
SEC"1";
"A"
$PN"1"31;
"B"
$PN"2"21;
%"CAP"
"1","(-5925,4150)","0","mstr_discrete","I204";
;
CDS_SEC"1"
PACK_TYPE"0805"
MATERIAL"X6S"
TOLERANCE"10%"
PART_NUMBER"C95333-007"
VALUE"10UF"
LOCATION"C6M5"
VOLTAGE"16V"
CDS_LIB"mstr_discrete"
CDS_LOCATION"C6M5"
SEC"1"
SEC_TYPE"0805";
"A"
$PN"1"31;
"B"
$PN"2"22;
%"CAP"
"1","(-5475,4150)","0","mstr_discrete","I205";
;
CDS_SEC"1"
PART_NUMBER"C95333-007"
MATERIAL"X6S"
PACK_TYPE"0805"
TOLERANCE"10%"
VOLTAGE"16V"
VALUE"10UF"
LOCATION"C4A19"
CDS_LIB"mstr_discrete"
CDS_LOCATION"C4A19"
SEC_TYPE"0805"
SEC"1";
"A"
$PN"1"31;
"B"
$PN"2"23;
%"GND"
"1","(-6750,3900)","0","mstr_symbols","I206";
;
BOM_COST"PVPP_KLM_VR"
ROOM"PVPP_KLM_VR"
BODY_TYPE"PLUMBING"
VOLTAGE"0"
CDS_LIB"mstr_symbols"
SIZE"1B"
HDL_POWER"GND";
"A\NAC"20;
%"GND"
"1","(-6375,3900)","0","mstr_symbols","I207";
;
HDL_POWER"GND"
SIZE"1B"
CDS_LIB"mstr_symbols"
VOLTAGE"0"
BODY_TYPE"PLUMBING"
ROOM"PVPP_KLM_VR"
BOM_COST"PVPP_KLM_VR";
"A\NAC"21;
%"GND"
"1","(-5925,3900)","0","mstr_symbols","I208";
;
SIZE"1B"
HDL_POWER"GND"
BODY_TYPE"PLUMBING"
CDS_LIB"mstr_symbols"
VOLTAGE"0"
ROOM"PVPP_KLM_VR"
BOM_COST"PVPP_KLM_VR";
"A\NAC"22;
%"GND"
"1","(-5475,3900)","0","mstr_symbols","I209";
;
HDL_POWER"GND"
SIZE"1B"
CDS_LIB"mstr_symbols"
VOLTAGE"0"
BODY_TYPE"PLUMBING"
ROOM"PVPP_KLM_VR"
BOM_COST"PVPP_KLM_VR";
"A\NAC"23;
%"CAPP"
"1","(-1450,3650)","0","mstr_discrete","I210";
;
CDS_SEC"1"
LOCATION"C6L8"
VALUE"220UF"
TOLERANCE"20%"
VOLTAGE"4V"
GROUP"PWR_BULK_CAP"
MATERIAL"POSCAP"
PACK_TYPE"7343"
PART_NUMBER"724613-067"
SEC_TYPE"7343"
SEC"1"
CDS_LOCATION"C6L8"
CDS_LIB"mstr_discrete";
"B"
$PN"2"9;
"A"
$PN"1"12;
%"CAP"
"2","(-2850,2450)","2","mstr_discrete","I211";
;
CDS_SEC"1"
PART_NUMBER"A36096-075"
VOLTAGE"50V"
PACK_TYPE"0402LF"
TOLERANCE"10%"
LOCATION"C4B9"
MATERIAL"X7R"
VALUE"2200PF"
ROOM"PVPP_KLM_VR"
SEC"1"
REUSE_ID"27"
BOM_COST"PVPP_KLM_VR"
SEC_TYPE"0402LF"
CDS_LOCATION"C4B9"
CDS_LIB"mstr_discrete";
"A"
$PN"1"42;
"B"
$PN"2"39;
%"CAP"
"2","(-2225,2825)","2","mstr_discrete","I212";
;
CDS_SEC"1"
PACK_TYPE"0402LF"
TOLERANCE"5%"
PART_NUMBER"A36095-026"
VALUE"100.0PF"
VOLTAGE"50V"
MATERIAL"COG"
LOCATION"C4B4"
ROOM"PVPP_KLM_VR"
CDS_LOCATION"C4B4"
BOM_COST"PVPP_KLM_VR"
CDS_LIB"mstr_discrete"
SEC"1"
REUSE_ID"27"
SEC_TYPE"0402LF";
"A"
$PN"1"45;
"B"
$PN"2"39;
%"RES"
"1","(-2150,2450)","0","mstr_discrete","I213";
;
CDS_SEC"1"
VALUE"7.87K"
LOCATION"R4B8"
PART_NUMBER"G21796-242"
PACK_TYPE"0402"
MATERIAL"CHIP"
TOLERANCE"1.0%"
WATTAGE"1/16W"
REUSE_ID"13"
SEC_TYPE"0402"
SEC"1"
ROOM"PVPP_KLM_VR"
CDS_LIB"mstr_discrete"
BOM_COST"PVPP_KLM_VR"
CDS_LOCATION"R4B8";
"B"
$PN"2"45;
"A"
$PN"1"42;
%"RES"
"1","(-1350,3050)","5","mstr_discrete","I214";
;
CDS_SEC"1"
PART_NUMBER"G21497-005"
MATERIAL"CHIP"
PACK_TYPE"0402"
TOLERANCE"5%"
VALUE"0.0"
LOCATION"R4B3"
WATTAGE"1/16W"
SEC"1"
SEC_TYPE"0402"
SPOF"TRUE"
CDS_LOCATION"R4B3"
ROOM"PVPP_KLM_VR"
CDS_LIB"mstr_discrete";
"B"
$PN"2"40;
"A"
$PN"1"12;
%"RES"
"2","(-1350,2175)","0","mstr_discrete","I215";
;
PART_NUMBER"G21796-040"
LOCATION"R4B5"
VALUE"20.0K"
TOLERANCE"1%"
PACK_TYPE"0402"
MATERIAL"CHIP"
WATTAGE"1/16W"
$SEC"1"
REUSE_ID"9"
CDS_SEC"1"
SPOF"TRUE"
BOM_COST"PVPP_KLM_VR"
ROOM"PVPP_KLM_VR"
CDS_LOCATION"R4B5"
CDS_LIB"mstr_discrete";
"A"
$PN"1"40;
"B"
$PN"2"45;
%"CAP"
"1","(-1025,1950)","0","mstr_discrete","I218";
;
CDS_SEC"1"
PART_NUMBER"A36096-075"
PACK_TYPE"0402LF"
MATERIAL"X7R"
TOLERANCE"10%"
VOLTAGE"50V"
VALUE"2200PF"
LOCATION"C4B7"
CDS_LIB"mstr_discrete"
ROOM"PVPP_KLM_VR"
CDS_LOCATION"C4B7"
SEC"1"
SEC_TYPE"0402LF"
REUSE_ID"26"
BOM_COST"PVPP_KLM_VR"
SPOF"TRUE";
"A"
$PN"1"41;
"B"
$PN"2"45;
%"RES"
"2","(-1025,2750)","0","mstr_discrete","I219";
;
CDS_SEC"1"
VALUE"1.0K"
PART_NUMBER"G85996-004"
MATERIAL"CHIP"
PACK_TYPE"0402"
WATTAGE"1/16W"
TOLERANCE"0.1%"
LOCATION"R4B9"
CDS_LIB"mstr_discrete"
ROOM"PVPP_KLM_VR"
CDS_LOCATION"R4B9"
SEC"1"
SEC_TYPE"0402"
REUSE_ID"9"
BOM_COST"PVPP_KLM_VR"
SPOF"TRUE";
"A"
$PN"1"40;
"B"
$PN"2"41;
%"RES"
"1","(-5925,2825)","0","mstr_discrete","I220";
;
CDS_SEC"1"
PACK_TYPE"0402"
TOLERANCE"5%"
MATERIAL"CHIP"
WATTAGE"1/16W"
PART_NUMBER"G21497-005"
LOCATION"R4B1"
VALUE"0.0"
SEC_TYPE"0402"
SEC"1"
ROOM"PVCCIN_CPU0_VR"
CDS_LOCATION"R4B1"
CDS_LIB"mstr_discrete";
"B"
$PN"2"32;
"A"
$PN"1"36;
%"AGND_SCSI"
"1","(-1350,1050)","0","mstr_symbols","I221";
;
HDL_POWER"AGND_PVPP_KLM"
VOLTAGE"0.0V"
ROOM"PVPP_KLM_VR"
BODY_TYPE"PLUMBING"
CDS_LIB"mstr_symbols"
BOM_COST"PVPP_KLM_VR";
"A"24;
%"SC22U16V5MX-4-GP"
"1","(-7050,4100)","0","w_hdl","I222";
;
CDS_SEC"1"
CDS_LOCATION"C22W5"
TYPE"X6S"
PACK_SIZE"0805"
TOLERANCE"20%"
RATED"16V"
LOCATION"C22W5"
ATTRIBUTE"22UF"
VALUE"SC22U16V5MX-4-GP"
PACK_TYPE"SMD-BCG5"
SEC"1"
SEC_TYPE"SMD-BCG5"
PART_NUMBER"078.22611.0811"
CDS_LIB"w_hdl"
CDS_LMAN_SYM_OUTLINE"-50,25,50,-25";
"2"
$PN"2"26;
"1"
$PN"1"31;
%"SC22U16V5MX-4-GP"
"1","(-7350,4100)","0","w_hdl","I223";
;
CDS_SEC"1"
CDS_LOCATION"C4B1"
ATTRIBUTE"22UF"
TOLERANCE"20%"
RATED"16V"
TYPE"X6S"
PACK_SIZE"0805"
LOCATION"C4B1"
VALUE"SC22U16V5MX-4-GP"
CDS_LMAN_SYM_OUTLINE"-50,25,50,-25"
CDS_LIB"w_hdl"
PART_NUMBER"078.22611.0811"
SEC_TYPE"SMD-BCG5"
SEC"1"
PACK_TYPE"SMD-BCG5";
"2"
$PN"2"25;
"1"
$PN"1"31;
%"GND"
"1","(-7350,3850)","0","mstr_symbols","I224";
;
HDL_POWER"GND"
SIZE"1B"
VOLTAGE"0"
BODY_TYPE"PLUMBING"
ROOM"PVPP_KLM_VR"
BOM_COST"PVPP_KLM_VR"
CDS_LIB"mstr_symbols";
"A\NAC"25;
%"GND"
"1","(-7050,3850)","0","mstr_symbols","I225";
;
HDL_POWER"GND"
SIZE"1B"
VOLTAGE"0"
BODY_TYPE"PLUMBING"
ROOM"PVPP_KLM_VR"
BOM_COST"PVPP_KLM_VR"
CDS_LIB"mstr_symbols";
"A\NAC"26;
%"RES"
"1","(-4150,4200)","0","mstr_discrete","I226";
;
PACK_TYPE"0603"
TOLERANCE"5.0%"
PART_NUMBER"G22178-002"
VALUE"0"
WATTAGE"1/10W"
LOCATION"R4B13"
MATERIAL"CHIP"
ROOM"NIC_SPRV"
BOM_COST"NT_GBE_BASE"
CDS_LIB"mstr_discrete"
SEC_TYPE"0603"
SEC"1"
CDS_SEC"1"
CDS_LOCATION"R4B13";
"B"
$PN"2"38;
"A"
$PN"1"43;
%"RES"
"2","(-1350,1450)","0","mstr_discrete","I227";
;
PART_NUMBER"G21796-161"
VALUE"6.19K"
TOLERANCE"1%"
WATTAGE"1/16W"
LOCATION"R4B4"
MATERIAL"CHIP"
PACK_TYPE"0402"
BOM_COST"IO_SLOT"
SEC"1"
SEC_TYPE"0402"
ROOM"IO_SLOT"
CDS_LIB"mstr_discrete"
CDS_SEC"1"
CDS_LOCATION"R4B4";
"A"
$PN"1"45;
"B"
$PN"2"24;
%"RES"
"2","(-4750,1650)","2","mstr_discrete","I228";
;
MATERIAL"CHIP"
PACK_TYPE"0402"
TOLERANCE"1.0%"
LOCATION"R4B6"
WATTAGE"1/16W"
CONFIG"64.39015.6DL"
NEW_VALUE"3.9K"
CDS_LOCATION"R4B6"
CDS_SEC"1"
$SEC"1"
CDS_LIB"mstr_discrete"
BOM_COST"PVPP_KLM_VR"
ROOM"PVPP_KLM_VR"
VALUE"7.87K"
PART_NUMBER"G21796-242";
"A"
$PN"1"46;
"B"
$PN"2"16;
%"GND"
"1","(-1450,550)","0","mstr_symbols","I27";
;
VOLTAGE"0"
CDS_LIB"mstr_symbols"
HDL_POWER"GND"
SIZE"1B"
BODY_TYPE"PLUMBING"
ROOM"PVPP_KLM_VR"
BOM_COST"PVPP_KLM_VR";
"A\NAC"27;
%"AGND_SCSI"
"1","(-900,550)","0","mstr_symbols","I28";
;
HDL_POWER"AGND_PVPP_KLM"
CDS_LIB"mstr_symbols"
BODY_TYPE"PLUMBING"
VOLTAGE"0.0V"
BOM_COST"PVPP_KLM_VR"
ROOM"PVPP_KLM_VR";
"A"28;
%"RES"
"1","(-1150,650)","0","mstr_discrete","I29";
;
CDS_LOCATION"R4B14"
PART_NUMBER"G21497-005"
VALUE"0.0"
WATTAGE"1/16W"
PACK_TYPE"0402"
TOLERANCE"5%"
LOCATION"R4B14"
MATERIAL"CHIP"
$SEC"1"
CDS_SEC"1"
CDS_LIB"mstr_discrete"
ROOM"PVPP_KLM_VR";
"B"
$PN"2"28;
"A"
$PN"1"27;
%"CAP"
"1","(-5125,725)","0","mstr_discrete","I84";
;
CDS_SEC"1"
PACK_TYPE"0603LF"
MATERIAL"X6S"
PART_NUMBER"E15431-001"
VOLTAGE"4V"
VALUE"10UF"
LOCATION"C3B2"
GROUP"PWR_MLCC_CAP"
TOLERANCE"20%"
CDS_LIB"mstr_discrete"
ROOM"PVPP_KLM_VR"
CDS_LOCATION"C3B2"
SEC"1"
SEC_TYPE"0603LF"
BOM_COST"MEM_VRD_PVPP_AB";
"A"
$PN"1"30;
"B"
$PN"2"29;
%"GND"
"1","(-8225,275)","0","mstr_symbols","I85";
;
ROOM"PVPP_KLM_VR"
BODY_TYPE"PLUMBING"
SIZE"1B"
CDS_LIB"mstr_symbols"
VOLTAGE"0"
BOM_COST"MEM_VRD_PVPP_AB"
HDL_POWER"GND";
"A\NAC"29;
%"CAP"
"1","(-5400,700)","0","mstr_discrete","I86";
;
VALUE"10UF"
VOLTAGE"4V"
PART_NUMBER"E15431-001"
LOCATION"C3A8"
MATERIAL"X6S"
TOLERANCE"20%"
PACK_TYPE"0603LF"
GROUP"PWR_MLCC_CAP"
ROOM"PVPP_KLM_VR"
CDS_LOCATION"C3A8"
$SEC"1"
CDS_SEC"1"
BOM_COST"MEM_VRD_PVPP_AB"
CDS_LIB"mstr_discrete";
"A"
$PN"1"30;
"B"
$PN"2"29;
%"CAP"
"1","(-5675,700)","0","mstr_discrete","I87";
;
LOCATION"C7L3"
MATERIAL"X6S"
PACK_TYPE"0603LF"
VALUE"10UF"
VOLTAGE"4V"
TOLERANCE"20%"
PART_NUMBER"E15431-001"
GROUP"PWR_MLCC_CAP"
CDS_SEC"1"
BOM_COST"MEM_VRD_PVPP_AB"
$SEC"1"
CDS_LOCATION"C7L3"
ROOM"PVPP_KLM_VR"
CDS_LIB"mstr_discrete";
"A"
$PN"1"30;
"B"
$PN"2"29;
%"CAP"
"1","(-5950,725)","0","mstr_discrete","I88";
;
VOLTAGE"4V"
PART_NUMBER"E15431-001"
VALUE"10UF"
TOLERANCE"20%"
MATERIAL"X6S"
PACK_TYPE"0603LF"
LOCATION"C7L2"
GROUP"PWR_MLCC_CAP"
CDS_SEC"1"
$SEC"1"
BOM_COST"MEM_VRD_PVPP_AB"
ROOM"PVPP_KLM_VR"
CDS_LOCATION"C7L2"
CDS_LIB"mstr_discrete";
"A"
$PN"1"30;
"B"
$PN"2"29;
%"CAP"
"1","(-6250,725)","0","mstr_discrete","I89";
;
VOLTAGE"4V"
LOCATION"C7L7"
VALUE"10UF"
PACK_TYPE"0603LF"
PART_NUMBER"E15431-001"
MATERIAL"X6S"
TOLERANCE"20%"
GROUP"PWR_MLCC_CAP"
CDS_SEC"1"
$SEC"1"
BOM_COST"MEM_VRD_PVPP_AB"
ROOM"PVPP_KLM_VR"
CDS_LOCATION"C7L7"
CDS_LIB"mstr_discrete";
"A"
$PN"1"30;
"B"
$PN"2"29;
%"CAP"
"1","(-6550,725)","0","mstr_discrete","I90";
;
VOLTAGE"4V"
LOCATION"C7L6"
VALUE"10UF"
TOLERANCE"20%"
MATERIAL"X6S"
PACK_TYPE"0603LF"
PART_NUMBER"E15431-001"
GROUP"PWR_MLCC_CAP"
BOM_COST"MEM_VRD_PVPP_AB"
CDS_SEC"1"
$SEC"1"
CDS_LOCATION"C7L6"
ROOM"PVPP_KLM_VR"
CDS_LIB"mstr_discrete";
"A"
$PN"1"30;
"B"
$PN"2"29;
%"CAP"
"1","(-6825,725)","0","mstr_discrete","I91";
;
VOLTAGE"4V"
PART_NUMBER"E15431-001"
VALUE"10UF"
LOCATION"C7M4"
TOLERANCE"20%"
MATERIAL"X6S"
PACK_TYPE"0603LF"
GROUP"PWR_MLCC_CAP"
BOM_COST"MEM_VRD_PVPP_AB"
CDS_SEC"1"
$SEC"1"
CDS_LOCATION"C7M4"
ROOM"PVPP_KLM_VR"
CDS_LIB"mstr_discrete";
"A"
$PN"1"30;
"B"
$PN"2"29;
%"CAP"
"1","(-7125,725)","0","mstr_discrete","I92";
;
VOLTAGE"4V"
PART_NUMBER"E15431-001"
PACK_TYPE"0603LF"
VALUE"10UF"
LOCATION"C7M3"
TOLERANCE"20%"
MATERIAL"X6S"
GROUP"PWR_MLCC_CAP"
$SEC"1"
CDS_SEC"1"
ROOM"PVPP_KLM_VR"
BOM_COST"MEM_VRD_PVPP_AB"
CDS_LOCATION"C7M3"
CDS_LIB"mstr_discrete";
"A"
$PN"1"30;
"B"
$PN"2"29;
%"CAP"
"1","(-7400,700)","0","mstr_discrete","I93";
;
VOLTAGE"4V"
PACK_TYPE"0603LF"
PART_NUMBER"E15431-001"
LOCATION"C3A4"
VALUE"10UF"
TOLERANCE"20%"
MATERIAL"X6S"
GROUP"PWR_MLCC_CAP"
CDS_SEC"1"
$SEC"1"
ROOM"PVPP_KLM_VR"
BOM_COST"MEM_VRD_PVPP_AB"
CDS_LOCATION"C3A4"
CDS_LIB"mstr_discrete";
"A"
$PN"1"30;
"B"
$PN"2"29;
%"CAP"
"1","(-7675,725)","0","mstr_discrete","I94";
;
VOLTAGE"4V"
PART_NUMBER"E15431-001"
TOLERANCE"20%"
MATERIAL"X6S"
PACK_TYPE"0603LF"
VALUE"10UF"
LOCATION"C3B1"
GROUP"PWR_MLCC_CAP"
CDS_LIB"mstr_discrete"
CDS_LOCATION"C3B1"
BOM_COST"MEM_VRD_PVPP_AB"
ROOM"PVPP_KLM_VR"
$SEC"1"
CDS_SEC"1";
"A"
$PN"1"30;
"B"
$PN"2"29;
%"CAP"
"1","(-7950,725)","0","mstr_discrete","I95";
;
VOLTAGE"4V"
TOLERANCE"20%"
MATERIAL"X6S"
VALUE"10UF"
PACK_TYPE"0603LF"
LOCATION"C3A7"
PART_NUMBER"E15431-001"
GROUP"PWR_MLCC_CAP"
CDS_LIB"mstr_discrete"
ROOM"PVPP_KLM_VR"
CDS_LOCATION"C3A7"
$SEC"1"
CDS_SEC"1"
BOM_COST"MEM_VRD_PVPP_AB";
"A"
$PN"1"30;
"B"
$PN"2"29;
%"PVPP_KLM"
"1","(-8225,1000)","0","mstr_symbols","I96";
;
BODY_TYPE"PLUMBING"
VOLTAGE"2.5V"
CDS_LIB"mstr_symbols"
HDL_POWER"PVPP_KLM"
ROOM"PVPP_KLM_VR"
BOM_COST"MEM_VRD_PVPP_AB";
"G\NAC"30;
%"CAP"
"1","(-8225,725)","0","mstr_discrete","I97";
;
TOLERANCE"20%"
VOLTAGE"4V"
LOCATION"C3A3"
MATERIAL"X6S"
PACK_TYPE"0603LF"
VALUE"10UF"
PART_NUMBER"E15431-001"
GROUP"PWR_MLCC_CAP"
CDS_LIB"mstr_discrete"
CDS_LOCATION"C3A3"
BOM_COST"MEM_VRD_PVPP_AB"
ROOM"PVPP_KLM_VR"
CDS_SEC"1"
$SEC"1";
"A"
$PN"1"30;
"B"
$PN"2"29;
END.
